(kicad_pcb
	(version 20260206)
	(generator "pcbnew")
	(generator_version "10.0")
	(general
		(thickness 1.6)
		(legacy_teardrops no)
	)
	(paper "A4")
	(title_block
		(title "03242023_DA0F0TMBIJ0_F0T_Motherboard_J_brd_V01_OCP.brd")
		(comment 1 "Grand Teton / footprints 3453-3455 of 6105")
	)
	(layers
		(0 "F.Cu" signal "TOP")
		(4 "In1.Cu" signal "GND")
		(6 "In2.Cu" signal "IN1")
		(8 "In3.Cu" signal "GND1")
		(10 "In4.Cu" signal "IN2")
		(12 "In5.Cu" signal "GND2")
		(14 "In6.Cu" signal "IN3")
		(16 "In7.Cu" signal "GND3")
		(18 "In8.Cu" signal "VCC")
		(20 "In9.Cu" signal "VCC1")
		(22 "In10.Cu" signal "GND4")
		(24 "In11.Cu" signal "IN4")
		(26 "In12.Cu" signal "GND5")
		(28 "In13.Cu" signal "IN5")
		(30 "In14.Cu" signal "GND6")
		(32 "In15.Cu" signal "IN6")
		(34 "In16.Cu" signal "GND7")
		(2 "B.Cu" signal "BOTTOM")
		(9 "F.Adhes" user "F.Adhesive")
		(11 "B.Adhes" user "B.Adhesive")
		(13 "F.Paste" user "Package Geometry/Pastemask Top")
		(15 "B.Paste" user "Package Geometry/Pastemask Bottom")
		(5 "F.SilkS" user "Ref Des/Silkscreen Top")
		(7 "B.SilkS" user "Ref Des/Silkscreen Bottom")
		(1 "F.Mask" user "Board Geometry/Soldermask Top")
		(3 "B.Mask" user "Board Geometry/Soldermask Bottom")
		(17 "Dwgs.User" user "User.Drawings")
		(19 "Cmts.User" user "User.Comments")
		(21 "Eco1.User" user "User.Eco1")
		(23 "Eco2.User" user "User.Eco2")
		(25 "Edge.Cuts" user "Board Geometry/Outline")
		(27 "Margin" user)
		(31 "F.CrtYd" user "Package Geometry/Place Bound Top")
		(29 "B.CrtYd" user "Package Geometry/Place Bound Bottom")
		(35 "F.Fab" user "Ref Des/Assembly Top")
		(33 "B.Fab" user "Ref Des/Assembly Bottom")
	)
	(footprint ""
		(layer "F.Cu")
		(at 362.14558 -408.544268)
		(property "Reference" "R4555"
			(at 0 0 0)
			(layer "F.SilkS")
			(hide yes)
			(effects
				(font
					(size 1.27 1.27)
				)
			)
		)
		(property "Value" ""
			(at 0 0 0)
			(layer "F.Fab")
			(effects
				(font
					(size 1.27 1.27)
				)
			)
		)
		(duplicate_pad_numbers_are_jumpers no)
		(fp_line
			(start -0.7874 -0.4064)
			(end 0.7874 -0.4064)
			(stroke
				(width 0.1524)
				(type default)
			)
			(layer "F.SilkS")
		)
		(fp_line
			(start -0.7874 0.4064)
			(end -0.7874 -0.4064)
			(stroke
				(width 0.1524)
				(type default)
			)
			(layer "F.SilkS")
		)
		(fp_line
			(start 0.7874 -0.4064)
			(end 0.7874 0.4064)
			(stroke
				(width 0.1524)
				(type default)
			)
			(layer "F.SilkS")
		)
		(fp_line
			(start 0.7874 0.4064)
			(end -0.7874 0.4064)
			(stroke
				(width 0.1524)
				(type default)
			)
			(layer "F.SilkS")
		)
		(fp_line
			(start -0.67945 -0.305054)
			(end -0.12065 -0.305054)
			(stroke
				(width 0.1)
				(type default)
			)
			(layer "F.Fab")
		)
		(fp_line
			(start -0.67945 0.3048)
			(end -0.67945 -0.305054)
			(stroke
				(width 0.1)
				(type default)
			)
			(layer "F.Fab")
		)
		(fp_line
			(start -0.12065 -0.305054)
			(end -0.12065 -0.2794)
			(stroke
				(width 0.1)
				(type default)
			)
			(layer "F.Fab")
		)
		(fp_line
			(start -0.12065 -0.2794)
			(end 0.12065 -0.2794)
			(stroke
				(width 0.1)
				(type default)
			)
			(layer "F.Fab")
		)
		(fp_line
			(start -0.12065 0.2794)
			(end -0.12065 0.3048)
			(stroke
				(width 0.1)
				(type default)
			)
			(layer "F.Fab")
		)
		(fp_line
			(start -0.12065 0.3048)
			(end -0.67945 0.3048)
			(stroke
				(width 0.1)
				(type default)
			)
			(layer "F.Fab")
		)
		(fp_line
			(start 0.120396 0.2794)
			(end -0.12065 0.2794)
			(stroke
				(width 0.1)
				(type default)
			)
			(layer "F.Fab")
		)
		(fp_line
			(start 0.120396 0.3048)
			(end 0.120396 0.2794)
			(stroke
				(width 0.1)
				(type default)
			)
			(layer "F.Fab")
		)
		(fp_line
			(start 0.12065 -0.3048)
			(end 0.67945 -0.3048)
			(stroke
				(width 0.1)
				(type default)
			)
			(layer "F.Fab")
		)
		(fp_line
			(start 0.12065 -0.2794)
			(end 0.12065 -0.3048)
			(stroke
				(width 0.1)
				(type default)
			)
			(layer "F.Fab")
		)
		(fp_line
			(start 0.67945 -0.3048)
			(end 0.67945 0.3048)
			(stroke
				(width 0.1)
				(type default)
			)
			(layer "F.Fab")
		)
		(fp_line
			(start 0.67945 0.3048)
			(end 0.120396 0.3048)
			(stroke
				(width 0.1)
				(type default)
			)
			(layer "F.Fab")
		)
		(pad "1" smd circle
			(at -0.40005 0)
			(size 0 0)
			(layers "F.Cu" "F.Mask" "F.Paste")
			(net "SWB_HSC_EN_BUF_R")
		)
		(pad "2" smd circle
			(at 0.40005 0)
			(size 0 0)
			(layers "F.Cu" "F.Mask" "F.Paste")
			(net "GND")
		)
	)
	(footprint ""
		(layer "F.Cu")
		(at 263.101582 -68.139056 180)
		(property "Reference" "PC113"
			(at 0 0 180)
			(layer "F.SilkS")
			(hide yes)
			(effects
				(font
					(size 1.27 1.27)
				)
			)
		)
		(property "Value" ""
			(at 0 0 180)
			(layer "F.Fab")
			(effects
				(font
					(size 1.27 1.27)
				)
			)
		)
		(duplicate_pad_numbers_are_jumpers no)
		(fp_line
			(start 0.7874 0.4064)
			(end -0.7874 0.4064)
			(stroke
				(width 0.1524)
				(type default)
			)
			(layer "F.SilkS")
		)
		(fp_line
			(start 0.7874 -0.4064)
			(end 0.7874 0.4064)
			(stroke
				(width 0.1524)
				(type default)
			)
			(layer "F.SilkS")
		)
		(fp_line
			(start -0.7874 0.4064)
			(end -0.7874 -0.4064)
			(stroke
				(width 0.1524)
				(type default)
			)
			(layer "F.SilkS")
		)
		(fp_line
			(start -0.7874 -0.4064)
			(end 0.7874 -0.4064)
			(stroke
				(width 0.1524)
				(type default)
			)
			(layer "F.SilkS")
		)
		(fp_line
			(start 0.67945 0.3048)
			(end 0.120396 0.3048)
			(stroke
				(width 0.1)
				(type default)
			)
			(layer "F.Fab")
		)
		(fp_line
			(start 0.67945 -0.3048)
			(end 0.67945 0.3048)
			(stroke
				(width 0.1)
				(type default)
			)
			(layer "F.Fab")
		)
		(fp_line
			(start 0.12065 -0.2794)
			(end 0.12065 -0.3048)
			(stroke
				(width 0.1)
				(type default)
			)
			(layer "F.Fab")
		)
		(fp_line
			(start 0.12065 -0.3048)
			(end 0.67945 -0.3048)
			(stroke
				(width 0.1)
				(type default)
			)
			(layer "F.Fab")
		)
		(fp_line
			(start 0.120396 0.3048)
			(end 0.120396 0.2794)
			(stroke
				(width 0.1)
				(type default)
			)
			(layer "F.Fab")
		)
		(fp_line
			(start 0.120396 0.2794)
			(end -0.12065 0.2794)
			(stroke
				(width 0.1)
				(type default)
			)
			(layer "F.Fab")
		)
		(fp_line
			(start -0.12065 0.3048)
			(end -0.67945 0.3048)
			(stroke
				(width 0.1)
				(type default)
			)
			(layer "F.Fab")
		)
		(fp_line
			(start -0.12065 0.2794)
			(end -0.12065 0.3048)
			(stroke
				(width 0.1)
				(type default)
			)
			(layer "F.Fab")
		)
		(fp_line
			(start -0.12065 -0.2794)
			(end 0.12065 -0.2794)
			(stroke
				(width 0.1)
				(type default)
			)
			(layer "F.Fab")
		)
		(fp_line
			(start -0.12065 -0.305054)
			(end -0.12065 -0.2794)
			(stroke
				(width 0.1)
				(type default)
			)
			(layer "F.Fab")
		)
		(fp_line
			(start -0.67945 0.3048)
			(end -0.67945 -0.305054)
			(stroke
				(width 0.1)
				(type default)
			)
			(layer "F.Fab")
		)
		(fp_line
			(start -0.67945 -0.305054)
			(end -0.12065 -0.305054)
			(stroke
				(width 0.1)
				(type default)
			)
			(layer "F.Fab")
		)
		(pad "1" smd circle
			(at -0.40005 0 180)
			(size 0 0)
			(layers "F.Cu" "F.Mask" "F.Paste")
			(net "P1V05_PCH_AUX_VCC")
		)
		(pad "2" smd circle
			(at 0.40005 0 180)
			(size 0 0)
			(layers "F.Cu" "F.Mask" "F.Paste")
			(net "GND")
		)
	)
	(footprint ""
		(layer "F.Cu")
		(at 118.804944 -75.031092 -90)
		(property "Reference" "C1321"
			(at 0 0 270)
			(layer "F.SilkS")
			(hide yes)
			(effects
				(font
					(size 1.27 1.27)
				)
			)
		)
		(property "Value" ""
			(at 0 0 270)
			(layer "F.Fab")
			(effects
				(font
					(size 1.27 1.27)
				)
			)
		)
		(duplicate_pad_numbers_are_jumpers no)
		(fp_line
			(start -0.7874 0.4064)
			(end -0.7874 -0.4064)
			(stroke
				(width 0.1524)
				(type default)
			)
			(layer "F.SilkS")
		)
		(fp_line
			(start 0.7874 0.4064)
			(end -0.7874 0.4064)
			(stroke
				(width 0.1524)
				(type default)
			)
			(layer "F.SilkS")
		)
		(fp_line
			(start -0.7874 -0.4064)
			(end 0.7874 -0.4064)
			(stroke
				(width 0.1524)
				(type default)
			)
			(layer "F.SilkS")
		)
		(fp_line
			(start 0.7874 -0.4064)
			(end 0.7874 0.4064)
			(stroke
				(width 0.1524)
				(type default)
			)
			(layer "F.SilkS")
		)
		(fp_line
			(start -0.67945 0.3048)
			(end -0.67945 -0.305054)
			(stroke
				(width 0.1)
				(type default)
			)
			(layer "F.Fab")
		)
		(fp_line
			(start -0.12065 0.3048)
			(end -0.67945 0.3048)
			(stroke
				(width 0.1)
				(type default)
			)
			(layer "F.Fab")
		)
		(fp_line
			(start 0.120396 0.3048)
			(end 0.120396 0.2794)
			(stroke
				(width 0.1)
				(type default)
			)
			(layer "F.Fab")
		)
		(fp_line
			(start 0.67945 0.3048)
			(end 0.120396 0.3048)
			(stroke
				(width 0.1)
				(type default)
			)
			(layer "F.Fab")
		)
		(fp_line
			(start -0.12065 0.2794)
			(end -0.12065 0.3048)
			(stroke
				(width 0.1)
				(type default)
			)
			(layer "F.Fab")
		)
		(fp_line
			(start 0.120396 0.2794)
			(end -0.12065 0.2794)
			(stroke
				(width 0.1)
				(type default)
			)
			(layer "F.Fab")
		)
		(fp_line
			(start -0.12065 -0.2794)
			(end 0.12065 -0.2794)
			(stroke
				(width 0.1)
				(type default)
			)
			(layer "F.Fab")
		)
		(fp_line
			(start 0.12065 -0.2794)
			(end 0.12065 -0.3048)
			(stroke
				(width 0.1)
				(type default)
			)
			(layer "F.Fab")
		)
		(fp_line
			(start 0.12065 -0.3048)
			(end 0.67945 -0.3048)
			(stroke
				(width 0.1)
				(type default)
			)
			(layer "F.Fab")
		)
		(fp_line
			(start 0.67945 -0.3048)
			(end 0.67945 0.3048)
			(stroke
				(width 0.1)
				(type default)
			)
			(layer "F.Fab")
		)
		(fp_line
			(start -0.67945 -0.305054)
			(end -0.12065 -0.305054)
			(stroke
				(width 0.1)
				(type default)
			)
			(layer "F.Fab")
		)
		(fp_line
			(start -0.12065 -0.305054)
			(end -0.12065 -0.2794)
			(stroke
				(width 0.1)
				(type default)
			)
			(layer "F.Fab")
		)
		(pad "1" smd circle
			(at -0.40005 0 270)
			(size 0 0)
			(layers "F.Cu" "F.Mask" "F.Paste")
			(net "P3V3_AUX")
		)
		(pad "2" smd circle
			(at 0.40005 0 270)
			(size 0 0)
			(layers "F.Cu" "F.Mask" "F.Paste")
			(net "GND")
		)
	)
)
